(kicad_pcb
	(version 20241229)
	(generator "pcbnew")
	(generator_version "9.0")
	(general
		(thickness 1.6296)
		(legacy_teardrops no)
	)
	(paper "A3")
	(title_block
		(title "Thunderbolt to 10GbE adapter")
		(date "2026-04-21")
		(rev "1.1.0")
		(company "Antmicro Ltd")
		(comment 1 "www.antmicro.com")
		(comment 9 "footprint 288 of 703 (U14), pads 324-400 of 503")
	)
	(layers
		(0 "F.Cu" signal)
		(4 "In1.Cu" signal)
		(6 "In2.Cu" signal)
		(8 "In3.Cu" signal)
		(10 "In4.Cu" signal)
		(12 "In5.Cu" signal)
		(14 "In6.Cu" signal)
		(2 "B.Cu" signal)
		(9 "F.Adhes" user "F.Adhesive")
		(11 "B.Adhes" user "B.Adhesive")
		(13 "F.Paste" user)
		(15 "B.Paste" user)
		(5 "F.SilkS" user "F.Silkscreen")
		(7 "B.SilkS" user "B.Silkscreen")
		(1 "F.Mask" user)
		(3 "B.Mask" user)
		(17 "Dwgs.User" user "User.Drawings")
		(19 "Cmts.User" user "User.Comments")
		(21 "Eco1.User" user "User.Eco1")
		(23 "Eco2.User" user "User.Eco2")
		(25 "Edge.Cuts" user)
		(27 "Margin" user)
		(31 "F.CrtYd" user "F.Courtyard")
		(29 "B.CrtYd" user "B.Courtyard")
		(35 "F.Fab" user)
		(33 "B.Fab" user)
	)
	(footprint "antmicro-footprints:FCBGA-503_22x22mm_Layout21x24_P1mm"
		(layer "F.Cu")
		(at 151.005 81.499999 -90)
		(property "Reference" "U14"
			(at -11.499999 11.005 0)
			(layer "F.SilkS")
			(effects
				(font
					(size 0.7 0.7)
					(thickness 0.15)
				)
				(justify left bottom)
			)
		)
		(property "Value" "EZX710AT2_S_LMR5"
			(at -11.4 12.5 270)
			(layer "F.Fab")
			(effects
				(font
					(size 0.7 0.7)
					(thickness 0.15)
				)
				(justify left bottom)
			)
		)
		(property "Datasheet" "https://www.google.com/url?sa=t&source=web&rct=j&opi=89978449&url=https://cdrdv2-public.intel.com/596333/596333_X710-TM4_Datasheet_v_2_4.pdf&ved=2ahUKEwiSuv20_sCOAxXVCRAIHdxGO_UQFnoECBEQAQ&usg=AOvVaw1CjGyrGWE8ZvOdw4VBsY6U"
			(at 0 0 270)
			(layer "F.Fab")
			(effects
				(font
					(size 0.7 0.7)
					(thickness 0.15)
				)
				(justify left bottom)
			)
		)
		(property "Description" "Ethernet ICs Intel Ethernet Controller 10 Gigabit X7"
			(at 0 0 270)
			(layer "F.Fab")
			(effects
				(font
					(size 0.7 0.7)
					(thickness 0.15)
				)
				(justify left bottom)
			)
		)
		(property "MPN" "EZX710AT2 S LMR5"
			(at 0 0 270)
			(unlocked yes)
			(layer "F.Fab")
			(hide yes)
			(effects
				(font
					(size 1 1)
					(thickness 0.15)
				)
			)
		)
		(property "Manufacturer" "Intel"
			(at 0 0 270)
			(unlocked yes)
			(layer "F.Fab")
			(hide yes)
			(effects
				(font
					(size 1 1)
					(thickness 0.15)
				)
			)
		)
		(property "Author" "Antmicro"
			(at 0 0 270)
			(unlocked yes)
			(layer "F.Fab")
			(hide yes)
			(effects
				(font
					(size 1 1)
					(thickness 0.15)
				)
			)
		)
		(property "License" "Apache-2.0"
			(at 0 0 270)
			(unlocked yes)
			(layer "F.Fab")
			(hide yes)
			(effects
				(font
					(size 1 1)
					(thickness 0.15)
				)
			)
		)
		(sheetname "/X710-AT2 power/")
		(sheetfile "x710-at2-power.kicad_sch")
		(attr smd)
		(pad "M20" smd circle
			(at -0.75 -0.435 270)
			(size 0.5 0.5)
			(layers "F.Cu" "F.Mask" "F.Paste")
			(net 23 "GND")
			(pinfunction "VSS")
			(pintype "passive")
		)
		(pad "M22" smd circle
			(at 0.25 -0.435 270)
			(size 0.5 0.5)
			(layers "F.Cu" "F.Mask" "F.Paste")
			(net 549 "unconnected-(U14E-RSVDM22_NC-PadM22)")
			(pinfunction "RSVDM22_NC")
			(pintype "passive+no_connect")
		)
		(pad "M24" smd circle
			(at 1.25 -0.435 270)
			(size 0.5 0.5)
			(layers "F.Cu" "F.Mask" "F.Paste")
			(net 564 "unconnected-(U14E-RSVDM24_NC-PadM24)")
			(pinfunction "RSVDM24_NC")
			(pintype "passive+no_connect")
		)
		(pad "M26" smd circle
			(at 2.25 -0.435 270)
			(size 0.5 0.5)
			(layers "F.Cu" "F.Mask" "F.Paste")
			(net 460 "unconnected-(U14E-RSVDM26_NC-PadM26)")
			(pinfunction "RSVDM26_NC")
			(pintype "passive+no_connect")
		)
		(pad "M28" smd circle
			(at 3.25 -0.435 270)
			(size 0.5 0.5)
			(layers "F.Cu" "F.Mask" "F.Paste")
			(net 494 "unconnected-(U14E-RSVDM28_NC-PadM28)")
			(pinfunction "RSVDM28_NC")
			(pintype "passive+no_connect")
		)
		(pad "M30" smd circle
			(at 4.25 -0.435 270)
			(size 0.5 0.5)
			(layers "F.Cu" "F.Mask" "F.Paste")
			(net 560 "unconnected-(U14G-RSVDM30_NC-PadM30)")
			(pinfunction "RSVDM30_NC")
			(pintype "passive+no_connect")
		)
		(pad "M32" smd circle
			(at 5.25 -0.435 270)
			(size 0.5 0.5)
			(layers "F.Cu" "F.Mask" "F.Paste")
			(net 570 "unconnected-(U14G-RSVDM32_NC-PadM32)")
			(pinfunction "RSVDM32_NC")
			(pintype "passive+no_connect")
		)
		(pad "M34" smd circle
			(at 6.25 -0.435 270)
			(size 0.5 0.5)
			(layers "F.Cu" "F.Mask" "F.Paste")
			(net 464 "unconnected-(U14F-RSVDM34_NC-PadM34)")
			(pinfunction "RSVDM34_NC")
			(pintype "passive+no_connect")
		)
		(pad "M36" smd circle
			(at 7.25 -0.435 270)
			(size 0.5 0.5)
			(layers "F.Cu" "F.Mask" "F.Paste")
			(net 472 "unconnected-(U14F-RSVDM36_NC-PadM36)")
			(pinfunction "RSVDM36_NC")
			(pintype "passive+no_connect")
		)
		(pad "M38" smd circle
			(at 8.25 -0.435 270)
			(size 0.5 0.5)
			(layers "F.Cu" "F.Mask" "F.Paste")
			(net 18 "+1V88")
			(pinfunction "VDDP2")
			(pintype "power_in")
		)
		(pad "M40" smd circle
			(at 9.25 -0.435 270)
			(size 0.5 0.5)
			(layers "F.Cu" "F.Mask" "F.Paste")
			(net 111 "/X710-AT2 10GbE/~{P0_INT}")
			(pinfunction "P0_INT_MLC")
			(pintype "passive")
		)
		(pad "M42" smd circle
			(at 10.25 -0.435 270)
			(size 0.5 0.5)
			(layers "F.Cu" "F.Mask" "F.Paste")
			(net 147 "/X710-AT2 Misc/MDIO.MDIO")
			(pinfunction "MDIO")
			(pintype "bidirectional")
		)
		(pad "N1" smd circle
			(at -10.25 0.43 270)
			(size 0.5 0.5)
			(layers "F.Cu" "F.Mask" "F.Paste")
			(net 102 "/X710-AT2 10GbE/MDIO0_SDA0")
			(pinfunction "MDIO0_SDA0")
			(pintype "bidirectional")
		)
		(pad "N3" smd circle
			(at -9.25 0.43 270)
			(size 0.5 0.5)
			(layers "F.Cu" "F.Mask" "F.Paste")
			(net 100 "/X710-AT2 10GbE/MDC0_SCL0")
			(pinfunction "MDC0_SCL0")
			(pintype "output")
		)
		(pad "N5" smd circle
			(at -8.25 0.43 270)
			(size 0.5 0.5)
			(layers "F.Cu" "F.Mask" "F.Paste")
			(net 574 "unconnected-(U14C-SDP3_0-PadN5)")
			(pinfunction "SDP3_0")
			(pintype "passive+no_connect")
		)
		(pad "N7" smd circle
			(at -7.25 0.43 270)
			(size 0.5 0.5)
			(layers "F.Cu" "F.Mask" "F.Paste")
			(net 496 "unconnected-(U14C-SDP3_1-PadN7)")
			(pinfunction "SDP3_1")
			(pintype "passive+no_connect")
		)
		(pad "N9" smd circle
			(at -6.25 0.43 270)
			(size 0.5 0.5)
			(layers "F.Cu" "F.Mask" "F.Paste")
			(net 95 "/X710-AT2 RSVD/RSVDN9_VSS")
			(pinfunction "RSVDN9_VSS")
			(pintype "passive")
		)
		(pad "N11" smd circle
			(at -5.25 0.43 270)
			(size 0.5 0.5)
			(layers "F.Cu" "F.Mask" "F.Paste")
			(net 1 "VCCA")
			(pinfunction "VCCA")
			(pintype "passive")
		)
		(pad "N13" smd circle
			(at -4.25 0.43 270)
			(size 0.5 0.5)
			(layers "F.Cu" "F.Mask" "F.Paste")
			(net 1 "VCCA")
			(pinfunction "VCCA")
			(pintype "passive")
		)
		(pad "N15" smd circle
			(at -3.25 0.43 270)
			(size 0.5 0.5)
			(layers "F.Cu" "F.Mask" "F.Paste")
			(net 1 "VCCA")
			(pinfunction "VCCA")
			(pintype "passive")
		)
		(pad "N17" smd circle
			(at -2.25 0.43 270)
			(size 0.5 0.5)
			(layers "F.Cu" "F.Mask" "F.Paste")
			(net 9 "VCCD")
			(pinfunction "VCCD")
			(pintype "passive")
		)
		(pad "N19" smd circle
			(at -1.25 0.43 270)
			(size 0.5 0.5)
			(layers "F.Cu" "F.Mask" "F.Paste")
			(net 9 "VCCD")
			(pinfunction "VCCD")
			(pintype "passive")
		)
		(pad "N21" smd circle
			(at -0.25 0.43 270)
			(size 0.5 0.5)
			(layers "F.Cu" "F.Mask" "F.Paste")
			(net 9 "VCCD")
			(pinfunction "VCCD")
			(pintype "passive")
		)
		(pad "N23" smd circle
			(at 0.75 0.43 270)
			(size 0.5 0.5)
			(layers "F.Cu" "F.Mask" "F.Paste")
			(net 533 "unconnected-(U14E-RSVDN23_NC-PadN23)")
			(pinfunction "RSVDN23_NC")
			(pintype "passive+no_connect")
		)
		(pad "N25" smd circle
			(at 1.75 0.43 270)
			(size 0.5 0.5)
			(layers "F.Cu" "F.Mask" "F.Paste")
			(net 577 "unconnected-(U14E-RSVDN25_NC-PadN25)")
			(pinfunction "RSVDN25_NC")
			(pintype "passive+no_connect")
		)
		(pad "N27" smd circle
			(at 2.75 0.43 270)
			(size 0.5 0.5)
			(layers "F.Cu" "F.Mask" "F.Paste")
			(net 452 "unconnected-(U14E-RSVDN27_NC-PadN27)")
			(pinfunction "RSVDN27_NC")
			(pintype "passive+no_connect")
		)
		(pad "N29" smd circle
			(at 3.75 0.43 270)
			(size 0.5 0.5)
			(layers "F.Cu" "F.Mask" "F.Paste")
			(net 576 "unconnected-(U14G-RSVDN29_NC-PadN29)")
			(pinfunction "RSVDN29_NC")
			(pintype "passive+no_connect")
		)
		(pad "N31" smd circle
			(at 4.75 0.43 270)
			(size 0.5 0.5)
			(layers "F.Cu" "F.Mask" "F.Paste")
			(net 503 "unconnected-(U14G-RSVDN31_NC-PadN31)")
			(pinfunction "RSVDN31_NC")
			(pintype "passive+no_connect")
		)
		(pad "N33" smd circle
			(at 5.75 0.43 270)
			(size 0.5 0.5)
			(layers "F.Cu" "F.Mask" "F.Paste")
			(net 525 "unconnected-(U14F-RSVDN33_NC-PadN33)")
			(pinfunction "RSVDN33_NC")
			(pintype "passive+no_connect")
		)
		(pad "N35" smd circle
			(at 6.75 0.43 270)
			(size 0.5 0.5)
			(layers "F.Cu" "F.Mask" "F.Paste")
			(net 474 "unconnected-(U14F-RSVDN35_NC-PadN35)")
			(pinfunction "RSVDN35_NC")
			(pintype "passive+no_connect")
		)
		(pad "N37" smd circle
			(at 7.75 0.43 270)
			(size 0.5 0.5)
			(layers "F.Cu" "F.Mask" "F.Paste")
			(net 23 "GND")
			(pinfunction "RSVDN37_VSS")
			(pintype "passive")
		)
		(pad "N39" smd circle
			(at 8.75 0.43 270)
			(size 0.5 0.5)
			(layers "F.Cu" "F.Mask" "F.Paste")
			(net 587 "unconnected-(U14F-P0_PTP_SYNC0-PadN39)")
			(pinfunction "P0_PTP_SYNC0")
			(pintype "passive+no_connect")
		)
		(pad "N41" smd circle
			(at 9.75 0.43 270)
			(size 0.5 0.5)
			(layers "F.Cu" "F.Mask" "F.Paste")
			(net 559 "unconnected-(U14F-P0_PTP_SYNC1-PadN41)")
			(pinfunction "P0_PTP_SYNC1")
			(pintype "passive+no_connect")
		)
		(pad "P2" smd circle
			(at -9.75 1.295 270)
			(size 0.5 0.5)
			(layers "F.Cu" "F.Mask" "F.Paste")
			(net 371 "/TB Controller/~{PE_WAKE}")
			(pinfunction "~{PE_WAKE}")
			(pintype "open_collector")
		)
		(pad "P4" smd circle
			(at -8.75 1.295 270)
			(size 0.5 0.5)
			(layers "F.Cu" "F.Mask" "F.Paste")
			(net 535 "unconnected-(U14C-SDP1_1-PadP4)")
			(pinfunction "SDP1_1")
			(pintype "passive+no_connect")
		)
		(pad "P6" smd circle
			(at -7.75 1.295 270)
			(size 0.5 0.5)
			(layers "F.Cu" "F.Mask" "F.Paste")
			(net 547 "unconnected-(U14C-SDP1_2-PadP6)")
			(pinfunction "SDP1_2")
			(pintype "passive+no_connect")
		)
		(pad "P8" smd circle
			(at -6.75 1.295 270)
			(size 0.5 0.5)
			(layers "F.Cu" "F.Mask" "F.Paste")
			(net 99 "/X710-AT2 RSVD/RSVDP8_VSS")
			(pinfunction "RSVDP8_VSS")
			(pintype "passive")
		)
		(pad "P10" smd circle
			(at -5.75 1.295 270)
			(size 0.5 0.5)
			(layers "F.Cu" "F.Mask" "F.Paste")
			(net 23 "GND")
			(pinfunction "VSS")
			(pintype "passive")
		)
		(pad "P12" smd circle
			(at -4.75 1.295 270)
			(size 0.5 0.5)
			(layers "F.Cu" "F.Mask" "F.Paste")
			(net 23 "GND")
			(pinfunction "VSS")
			(pintype "passive")
		)
		(pad "P14" smd circle
			(at -3.75 1.295 270)
			(size 0.5 0.5)
			(layers "F.Cu" "F.Mask" "F.Paste")
			(net 23 "GND")
			(pinfunction "VSS")
			(pintype "passive")
		)
		(pad "P16" smd circle
			(at -2.75 1.295 270)
			(size 0.5 0.5)
			(layers "F.Cu" "F.Mask" "F.Paste")
			(net 23 "GND")
			(pinfunction "VSS")
			(pintype "passive")
		)
		(pad "P18" smd circle
			(at -1.75 1.295 270)
			(size 0.5 0.5)
			(layers "F.Cu" "F.Mask" "F.Paste")
			(net 23 "GND")
			(pinfunction "VSS")
			(pintype "passive")
		)
		(pad "P20" smd circle
			(at -0.75 1.295 270)
			(size 0.5 0.5)
			(layers "F.Cu" "F.Mask" "F.Paste")
			(net 23 "GND")
			(pinfunction "VSS")
			(pintype "passive")
		)
		(pad "P22" smd circle
			(at 0.25 1.295 270)
			(size 0.5 0.5)
			(layers "F.Cu" "F.Mask" "F.Paste")
			(net 97 "/X710-AT2 RSVD/RSVDP22_VSS")
			(pinfunction "RSVDP22_VSS")
			(pintype "passive")
		)
		(pad "P24" smd circle
			(at 1.25 1.295 270)
			(size 0.5 0.5)
			(layers "F.Cu" "F.Mask" "F.Paste")
			(net 501 "unconnected-(U14E-RSVDP24_NC-PadP24)")
			(pinfunction "RSVDP24_NC")
			(pintype "passive+no_connect")
		)
		(pad "P26" smd circle
			(at 2.25 1.295 270)
			(size 0.5 0.5)
			(layers "F.Cu" "F.Mask" "F.Paste")
			(net 477 "unconnected-(U14E-RSVDP26_NC-PadP26)")
			(pinfunction "RSVDP26_NC")
			(pintype "passive+no_connect")
		)
		(pad "P28" smd circle
			(at 3.25 1.295 270)
			(size 0.5 0.5)
			(layers "F.Cu" "F.Mask" "F.Paste")
			(net 502 "unconnected-(U14E-RSVDP28_NC-PadP28)")
			(pinfunction "RSVDP28_NC")
			(pintype "passive+no_connect")
		)
		(pad "P30" smd circle
			(at 4.25 1.295 270)
			(size 0.5 0.5)
			(layers "F.Cu" "F.Mask" "F.Paste")
			(net 520 "unconnected-(U14G-RSVDP30_NC-PadP30)")
			(pinfunction "RSVDP30_NC")
			(pintype "passive+no_connect")
		)
		(pad "P32" smd circle
			(at 5.25 1.295 270)
			(size 0.5 0.5)
			(layers "F.Cu" "F.Mask" "F.Paste")
			(net 454 "unconnected-(U14G-RSVDP32_NC-PadP32)")
			(pinfunction "RSVDP32_NC")
			(pintype "passive+no_connect")
		)
		(pad "P34" smd circle
			(at 6.25 1.295 270)
			(size 0.5 0.5)
			(layers "F.Cu" "F.Mask" "F.Paste")
			(net 527 "unconnected-(U14F-RSVDP34_NC-PadP34)")
			(pinfunction "RSVDP34_NC")
			(pintype "passive+no_connect")
		)
		(pad "P36" smd circle
			(at 7.25 1.295 270)
			(size 0.5 0.5)
			(layers "F.Cu" "F.Mask" "F.Paste")
			(net 506 "unconnected-(U14F-RSVDP36_NC-PadP36)")
			(pinfunction "RSVDP36_NC")
			(pintype "passive+no_connect")
		)
		(pad "P38" smd circle
			(at 8.25 1.295 270)
			(size 0.5 0.5)
			(layers "F.Cu" "F.Mask" "F.Paste")
			(net 23 "GND")
			(pinfunction "RSVDP38_VSS")
			(pintype "passive")
		)
		(pad "P40" smd circle
			(at 9.25 1.295 270)
			(size 0.5 0.5)
			(layers "F.Cu" "F.Mask" "F.Paste")
			(net 81 "/X710-AT2 Misc/FLSH_SCK")
			(pinfunction "FLSH_SCK")
			(pintype "tri_state")
		)
		(pad "P42" smd circle
			(at 10.25 1.295 270)
			(size 0.5 0.5)
			(layers "F.Cu" "F.Mask" "F.Paste")
			(net 352 "/X710 flash memory/FLASH.MOSI")
			(pinfunction "FLSH_SI")
			(pintype "tri_state")
		)
		(pad "R1" smd circle
			(at -10.25 2.16 270)
			(size 0.5 0.5)
			(layers "F.Cu" "F.Mask" "F.Paste")
			(net 392 "/TB Controller/~{PE_RST}")
			(pinfunction "~{PE_RST}")
			(pintype "input")
		)
		(pad "R3" smd circle
			(at -9.25 2.16 270)
			(size 0.5 0.5)
			(layers "F.Cu" "F.Mask" "F.Paste")
			(net 554 "unconnected-(U14C-LED3_0-PadR3)")
			(pinfunction "LED3_0")
			(pintype "passive+no_connect")
		)
		(pad "R5" smd circle
			(at -8.25 2.16 270)
			(size 0.5 0.5)
			(layers "F.Cu" "F.Mask" "F.Paste")
			(net 481 "unconnected-(U14C-LED3_1-PadR5)")
			(pinfunction "LED3_1")
			(pintype "passive+no_connect")
		)
		(pad "R7" smd circle
			(at -7.25 2.16 270)
			(size 0.5 0.5)
			(layers "F.Cu" "F.Mask" "F.Paste")
			(net 491 "unconnected-(U14C-SDP1_0-PadR7)")
			(pinfunction "SDP1_0")
			(pintype "passive+no_connect")
		)
		(pad "R9" smd circle
			(at -6.25 2.16 270)
			(size 0.5 0.5)
			(layers "F.Cu" "F.Mask" "F.Paste")
			(net 553 "unconnected-(U14E-RSVDR9_NC-PadR9)")
			(pinfunction "RSVDR9_NC")
			(pintype "passive+no_connect")
		)
		(pad "R11" smd circle
			(at -5.25 2.16 270)
			(size 0.5 0.5)
			(layers "F.Cu" "F.Mask" "F.Paste")
			(net 7 "+3V3")
			(pinfunction "VCC3P3")
			(pintype "passive")
		)
		(pad "R13" smd circle
			(at -4.25 2.16 270)
			(size 0.5 0.5)
			(layers "F.Cu" "F.Mask" "F.Paste")
			(net 9 "VCCD")
			(pinfunction "VCCD")
			(pintype "passive")
		)
		(pad "R15" smd circle
			(at -3.25 2.16 270)
			(size 0.5 0.5)
			(layers "F.Cu" "F.Mask" "F.Paste")
			(net 9 "VCCD")
			(pinfunction "VCCD")
			(pintype "passive")
		)
		(pad "R17" smd circle
			(at -2.25 2.16 270)
			(size 0.5 0.5)
			(layers "F.Cu" "F.Mask" "F.Paste")
			(net 9 "VCCD")
			(pinfunction "VCCD")
			(pintype "passive")
		)
		(pad "R19" smd circle
			(at -1.25 2.16 270)
			(size 0.5 0.5)
			(layers "F.Cu" "F.Mask" "F.Paste")
			(net 9 "VCCD")
			(pinfunction "VCCD")
			(pintype "passive")
		)
		(pad "R21" smd circle
			(at -0.25 2.16 270)
			(size 0.5 0.5)
			(layers "F.Cu" "F.Mask" "F.Paste")
			(net 9 "VCCD")
			(pinfunction "VCCD")
			(pintype "passive")
		)
		(pad "R23" smd circle
			(at 0.75 2.16 270)
			(size 0.5 0.5)
			(layers "F.Cu" "F.Mask" "F.Paste")
			(net 483 "unconnected-(U14E-RSVDR23_NC-PadR23)")
			(pinfunction "RSVDR23_NC")
			(pintype "passive+no_connect")
		)
		(pad "R25" smd circle
			(at 1.75 2.16 270)
			(size 0.5 0.5)
			(layers "F.Cu" "F.Mask" "F.Paste")
			(net 497 "unconnected-(U14E-RSVDR25_NC-PadR25)")
			(pinfunction "RSVDR25_NC")
			(pintype "passive+no_connect")
		)
		(pad "R27" smd circle
			(at 2.75 2.16 270)
			(size 0.5 0.5)
			(layers "F.Cu" "F.Mask" "F.Paste")
			(net 478 "unconnected-(U14E-RSVDR27_NC-PadR27)")
			(pinfunction "RSVDR27_NC")
			(pintype "passive+no_connect")
		)
		(pad "R29" smd circle
			(at 3.75 2.16 270)
			(size 0.5 0.5)
			(layers "F.Cu" "F.Mask" "F.Paste")
			(net 449 "unconnected-(U14G-RSVDR29_NC-PadR29)")
			(pinfunction "RSVDR29_NC")
			(pintype "passive+no_connect")
		)
		(pad "R31" smd circle
			(at 4.75 2.16 270)
			(size 0.5 0.5)
			(layers "F.Cu" "F.Mask" "F.Paste")
			(net 492 "unconnected-(U14G-RSVDR31_NC-PadR31)")
			(pinfunction "RSVDR31_NC")
			(pintype "passive+no_connect")
		)
		(pad "R33" smd circle
			(at 5.75 2.16 270)
			(size 0.5 0.5)
			(layers "F.Cu" "F.Mask" "F.Paste")
			(net 455 "unconnected-(U14F-RSVDR33_NC-PadR33)")
			(pinfunction "RSVDR33_NC")
			(pintype "passive+no_connect")
		)
		(pad "R35" smd circle
			(at 6.75 2.16 270)
			(size 0.5 0.5)
			(layers "F.Cu" "F.Mask" "F.Paste")
			(net 23 "GND")
			(pinfunction "VSS")
			(pintype "passive")
		)
		(pad "R37" smd circle
			(at 7.75 2.16 270)
			(size 0.5 0.5)
			(layers "F.Cu" "F.Mask" "F.Paste")
			(net 488 "unconnected-(U14F-RSVDR37_NC-PadR37)")
			(pinfunction "RSVDR37_NC")
			(pintype "passive+no_connect")
		)
		(pad "R39" smd circle
			(at 8.75 2.16 270)
			(size 0.5 0.5)
			(layers "F.Cu" "F.Mask" "F.Paste")
			(net 444 "Net-(U14D-SMBCLK)")
			(pinfunction "SMBCLK")
			(pintype "open_collector")
		)
		(pad "R41" smd circle
			(at 9.75 2.16 270)
			(size 0.5 0.5)
			(layers "F.Cu" "F.Mask" "F.Paste")
			(net 350 "/X710 flash memory/FLASH.~{CE}")
			(pinfunction "~{FLSH_CE}")
			(pintype "tri_state")
		)
		(pad "T2" smd circle
			(at -9.75 3.025 270)
			(size 0.5 0.5)
			(layers "F.Cu" "F.Mask" "F.Paste")
			(net 7 "+3V3")
			(pinfunction "VCC3P3_SVR")
			(pintype "power_in")
		)
		(pad "T4" smd circle
			(at -8.75 3.025 270)
			(size 0.5 0.5)
			(layers "F.Cu" "F.Mask" "F.Paste")
			(net 67 "/2xRJ45/~{P1_LED_ACT}")
			(pinfunction "LED2_0")
			(pintype "output")
		)
	)
)
